# SCM (Grand Teton) — schematic netlist excerpt (pin names and nets, part order shuffled) for the footprints in the layout excerpt that follows; sources: Cadence DE-HDL packaged netlist, KiCad conversion of 12092022_DA0F0TMDCD0_F0T_Management_Board_D_brd_V3_OCP.brd

R153  Q_RES  33.2 1% CHIP  pkg 0402LF  page 12 : A = SMB_BMC_MM16_SDA ; B = SMB_BMC_MM16_R_SDA
C46  Q_CAP  1UF 25V 10% X6S  pkg C0402  page 17 : A = P1V8_STBY_AVDDPLL ; B = GND

(kicad_pcb
	(version 20260206)
	(generator "pcbnew")
	(generator_version "10.0")
	(general
		(thickness 1.6)
		(legacy_teardrops no)
	)
	(paper "A4")
	(title_block
		(title "12092022_DA0F0TMDCD0_F0T_Management_Board_D_brd_V3_OCP.brd")
		(comment 1 "Grand Teton / footprints 871-872 of 1440")
	)
	(layers
		(0 "F.Cu" signal "TOP")
		(4 "In1.Cu" signal "GND")
		(6 "In2.Cu" signal "IN1")
		(8 "In3.Cu" signal "GND1")
		(10 "In4.Cu" signal "IN2")
		(12 "In5.Cu" signal "VCC")
		(14 "In6.Cu" signal "VCC1")
		(16 "In7.Cu" signal "IN3")
		(18 "In8.Cu" signal "GND2")
		(20 "In9.Cu" signal "IN4")
		(22 "In10.Cu" signal "GND3")
		(2 "B.Cu" signal "BOTTOM")
		(9 "F.Adhes" user "F.Adhesive")
		(11 "B.Adhes" user "B.Adhesive")
		(13 "F.Paste" user "Package Geometry/Pastemask Top")
		(15 "B.Paste" user "Package Geometry/Pastemask Bottom")
		(5 "F.SilkS" user "Ref Des/Silkscreen Top")
		(7 "B.SilkS" user "Ref Des/Silkscreen Bottom")
		(1 "F.Mask" user "Board Geometry/Soldermask Top")
		(3 "B.Mask" user "Board Geometry/Soldermask Bottom")
		(17 "Dwgs.User" user "User.Drawings")
		(19 "Cmts.User" user "User.Comments")
		(21 "Eco1.User" user "User.Eco1")
		(23 "Eco2.User" user "User.Eco2")
		(25 "Edge.Cuts" user "Board Geometry/Outline")
		(27 "Margin" user)
		(31 "F.CrtYd" user "Package Geometry/Place Bound Top")
		(29 "B.CrtYd" user "Package Geometry/Place Bound Bottom")
		(35 "F.Fab" user "Ref Des/Assembly Top")
		(33 "B.Fab" user "Ref Des/Assembly Bottom")
	)
	(footprint ""
		(layer "B.Cu")
		(at 49.53 -34.671 -90)
		(property "Reference" "R153"
			(at 0 0 90)
			(layer "B.SilkS")
			(hide yes)
			(effects
				(font
					(size 1.27 1.27)
				)
				(justify mirror)
			)
		)
		(property "Value" ""
			(at 0 0 90)
			(layer "B.Fab")
			(effects
				(font
					(size 1.27 1.27)
				)
				(justify mirror)
			)
		)
		(duplicate_pad_numbers_are_jumpers no)
		(fp_line
			(start -0.7874 0.4064)
			(end 0.7874 0.4064)
			(stroke
				(width 0.1524)
				(type default)
			)
			(layer "B.SilkS")
		)
		(fp_line
			(start 0.7874 0.4064)
			(end 0.7874 -0.4064)
			(stroke
				(width 0.1524)
				(type default)
			)
			(layer "B.SilkS")
		)
		(fp_line
			(start -0.7874 -0.4064)
			(end -0.7874 0.4064)
			(stroke
				(width 0.1524)
				(type default)
			)
			(layer "B.SilkS")
		)
		(fp_line
			(start 0.7874 -0.4064)
			(end -0.7874 -0.4064)
			(stroke
				(width 0.1524)
				(type default)
			)
			(layer "B.SilkS")
		)
		(fp_line
			(start -0.67945 0.3048)
			(end -0.120396 0.3048)
			(stroke
				(width 0.1)
				(type default)
			)
			(layer "B.Fab")
		)
		(fp_line
			(start -0.120396 0.3048)
			(end -0.120396 0.2794)
			(stroke
				(width 0.1)
				(type default)
			)
			(layer "B.Fab")
		)
		(fp_line
			(start 0.12065 0.3048)
			(end 0.67945 0.3048)
			(stroke
				(width 0.1)
				(type default)
			)
			(layer "B.Fab")
		)
		(fp_line
			(start 0.67945 0.3048)
			(end 0.67945 -0.305054)
			(stroke
				(width 0.1)
				(type default)
			)
			(layer "B.Fab")
		)
		(fp_line
			(start -0.120396 0.2794)
			(end 0.12065 0.2794)
			(stroke
				(width 0.1)
				(type default)
			)
			(layer "B.Fab")
		)
		(fp_line
			(start 0.12065 0.2794)
			(end 0.12065 0.3048)
			(stroke
				(width 0.1)
				(type default)
			)
			(layer "B.Fab")
		)
		(fp_line
			(start -0.12065 -0.2794)
			(end -0.12065 -0.3048)
			(stroke
				(width 0.1)
				(type default)
			)
			(layer "B.Fab")
		)
		(fp_line
			(start 0.12065 -0.2794)
			(end -0.12065 -0.2794)
			(stroke
				(width 0.1)
				(type default)
			)
			(layer "B.Fab")
		)
		(fp_line
			(start -0.67945 -0.3048)
			(end -0.67945 0.3048)
			(stroke
				(width 0.1)
				(type default)
			)
			(layer "B.Fab")
		)
		(fp_line
			(start -0.12065 -0.3048)
			(end -0.67945 -0.3048)
			(stroke
				(width 0.1)
				(type default)
			)
			(layer "B.Fab")
		)
		(fp_line
			(start 0.12065 -0.305054)
			(end 0.12065 -0.2794)
			(stroke
				(width 0.1)
				(type default)
			)
			(layer "B.Fab")
		)
		(fp_line
			(start 0.67945 -0.305054)
			(end 0.12065 -0.305054)
			(stroke
				(width 0.1)
				(type default)
			)
			(layer "B.Fab")
		)
		(pad "1" smd circle
			(at 0.40005 0 90)
			(size 0 0)
			(layers "B.Cu" "B.Mask" "B.Paste")
			(net "SMB_BMC_MM16_SDA")
		)
		(pad "2" smd circle
			(at -0.40005 0 90)
			(size 0 0)
			(layers "B.Cu" "B.Mask" "B.Paste")
			(net "SMB_BMC_MM16_R_SDA")
		)
	)
	(footprint ""
		(layer "B.Cu")
		(at 67.529964 -37.0205 -90)
		(property "Reference" "C46"
			(at 0 0 90)
			(layer "B.SilkS")
			(hide yes)
			(effects
				(font
					(size 1.27 1.27)
				)
				(justify mirror)
			)
		)
		(property "Value" ""
			(at 0 0 90)
			(layer "B.Fab")
			(effects
				(font
					(size 1.27 1.27)
				)
				(justify mirror)
			)
		)
		(duplicate_pad_numbers_are_jumpers no)
		(fp_line
			(start -0.7874 0.4064)
			(end 0.7874 0.4064)
			(stroke
				(width 0.1524)
				(type default)
			)
			(layer "B.SilkS")
		)
		(fp_line
			(start 0.7874 0.4064)
			(end 0.7874 -0.4064)
			(stroke
				(width 0.1524)
				(type default)
			)
			(layer "B.SilkS")
		)
		(fp_line
			(start -0.7874 -0.4064)
			(end -0.7874 0.4064)
			(stroke
				(width 0.1524)
				(type default)
			)
			(layer "B.SilkS")
		)
		(fp_line
			(start 0.7874 -0.4064)
			(end -0.7874 -0.4064)
			(stroke
				(width 0.1524)
				(type default)
			)
			(layer "B.SilkS")
		)
		(fp_line
			(start -0.67945 0.3048)
			(end -0.120396 0.3048)
			(stroke
				(width 0.1)
				(type default)
			)
			(layer "B.Fab")
		)
		(fp_line
			(start -0.120396 0.3048)
			(end -0.120396 0.2794)
			(stroke
				(width 0.1)
				(type default)
			)
			(layer "B.Fab")
		)
		(fp_line
			(start 0.12065 0.3048)
			(end 0.67945 0.3048)
			(stroke
				(width 0.1)
				(type default)
			)
			(layer "B.Fab")
		)
		(fp_line
			(start 0.67945 0.3048)
			(end 0.67945 -0.305054)
			(stroke
				(width 0.1)
				(type default)
			)
			(layer "B.Fab")
		)
		(fp_line
			(start -0.120396 0.2794)
			(end 0.12065 0.2794)
			(stroke
				(width 0.1)
				(type default)
			)
			(layer "B.Fab")
		)
		(fp_line
			(start 0.12065 0.2794)
			(end 0.12065 0.3048)
			(stroke
				(width 0.1)
				(type default)
			)
			(layer "B.Fab")
		)
		(fp_line
			(start -0.12065 -0.2794)
			(end -0.12065 -0.3048)
			(stroke
				(width 0.1)
				(type default)
			)
			(layer "B.Fab")
		)
		(fp_line
			(start 0.12065 -0.2794)
			(end -0.12065 -0.2794)
			(stroke
				(width 0.1)
				(type default)
			)
			(layer "B.Fab")
		)
		(fp_line
			(start -0.67945 -0.3048)
			(end -0.67945 0.3048)
			(stroke
				(width 0.1)
				(type default)
			)
			(layer "B.Fab")
		)
		(fp_line
			(start -0.12065 -0.3048)
			(end -0.67945 -0.3048)
			(stroke
				(width 0.1)
				(type default)
			)
			(layer "B.Fab")
		)
		(fp_line
			(start 0.12065 -0.305054)
			(end 0.12065 -0.2794)
			(stroke
				(width 0.1)
				(type default)
			)
			(layer "B.Fab")
		)
		(fp_line
			(start 0.67945 -0.305054)
			(end 0.12065 -0.305054)
			(stroke
				(width 0.1)
				(type default)
			)
			(layer "B.Fab")
		)
		(pad "1" smd circle
			(at 0.40005 0 90)
			(size 0 0)
			(layers "B.Cu" "B.Mask" "B.Paste")
			(net "P1V8_STBY_AVDDPLL")
		)
		(pad "2" smd circle
			(at -0.40005 0 90)
			(size 0 0)
			(layers "B.Cu" "B.Mask" "B.Paste")
			(net "GND")
		)
	)
)
